(kicad_pcb
	(version 20241229)
	(generator "pcbnew")
	(generator_version "9.0")
	(general
		(thickness 1.711)
		(legacy_teardrops no)
	)
	(paper "A4")
	(title_block
		(title "Antmicro Baseboard for Jetson AGX Thor")
		(date "2026-02-18")
		(rev "1.1.0")
		(company "Antmicro Ltd")
		(comment 1 "www.antmicro.com")
		(comment 9 "footprints 311-315 of 1170")
	)
	(layers
		(0 "F.Cu" signal)
		(4 "In1.Cu" signal)
		(6 "In2.Cu" signal)
		(8 "In3.Cu" signal)
		(10 "In4.Cu" jumper)
		(12 "In5.Cu" signal)
		(14 "In6.Cu" signal)
		(16 "In7.Cu" signal)
		(18 "In8.Cu" signal)
		(2 "B.Cu" signal)
		(9 "F.Adhes" user "F.Adhesive")
		(11 "B.Adhes" user "B.Adhesive")
		(13 "F.Paste" user)
		(15 "B.Paste" user)
		(5 "F.SilkS" user "F.Silkscreen")
		(7 "B.SilkS" user "B.Silkscreen")
		(1 "F.Mask" user)
		(3 "B.Mask" user)
		(17 "Dwgs.User" user "User.Drawings")
		(19 "Cmts.User" user "User.Comments")
		(21 "Eco1.User" user "User.Eco1")
		(23 "Eco2.User" user "User.Eco2")
		(25 "Edge.Cuts" user)
		(27 "Margin" user)
		(31 "F.CrtYd" user "F.Courtyard")
		(29 "B.CrtYd" user "B.Courtyard")
		(35 "F.Fab" user)
		(33 "B.Fab" user)
	)
	(footprint "antmicro-footprints:C_0805_2012Metric"
		(layer "F.Cu")
		(at 162.25 73.3 -90)
		(descr "Capacitor SMD 0805")
		(tags "capacitor SMD 0805")
		(property "Reference" "C283"
			(at -4.9 0.35 90)
			(layer "F.SilkS")
			(effects
				(font
					(size 0.7 0.7)
					(thickness 0.15)
				)
				(justify right top)
			)
		)
		(property "Value" "C_22u_25V_0805"
			(at -2.055717 1.963152 90)
			(layer "F.Fab")
			(effects
				(font
					(size 0.7 0.7)
					(thickness 0.15)
				)
				(justify right top)
			)
		)
		(property "Datasheet" "https://product.samsungsem.com/mlcc/CL21A226MAYNNN.do"
			(at 0 0 90)
			(layer "F.Fab")
			(hide yes)
			(effects
				(font
					(size 1.27 1.27)
					(thickness 0.15)
				)
			)
		)
		(property "Description" "SMT Multilayer Ceramic Capacitor, 22uF, +/-20%, 25V, X5R, 0805 [2012 Metric]"
			(at 0 0 90)
			(layer "F.Fab")
			(hide yes)
			(effects
				(font
					(size 1.27 1.27)
					(thickness 0.15)
				)
			)
		)
		(property "MPN" "CL21A226MAYNNNE"
			(at 0 0 270)
			(unlocked yes)
			(layer "F.Fab")
			(hide yes)
			(effects
				(font
					(size 1 1)
					(thickness 0.15)
				)
			)
		)
		(property "Manufacturer" "Samsung Electro-Mechanics"
			(at 0 0 270)
			(unlocked yes)
			(layer "F.Fab")
			(hide yes)
			(effects
				(font
					(size 1 1)
					(thickness 0.15)
				)
			)
		)
		(property "License" "Apache-2.0"
			(at 0 0 270)
			(unlocked yes)
			(layer "F.Fab")
			(hide yes)
			(effects
				(font
					(size 1 1)
					(thickness 0.15)
				)
			)
		)
		(property "Author" "Antmicro"
			(at 0 0 270)
			(unlocked yes)
			(layer "F.Fab")
			(hide yes)
			(effects
				(font
					(size 1 1)
					(thickness 0.15)
				)
			)
		)
		(property "Val" "22u"
			(at 0 0 270)
			(unlocked yes)
			(layer "F.Fab")
			(hide yes)
			(effects
				(font
					(size 1 1)
					(thickness 0.15)
				)
			)
		)
		(property "Voltage" "25V"
			(at 0 0 270)
			(unlocked yes)
			(layer "F.Fab")
			(hide yes)
			(effects
				(font
					(size 1 1)
					(thickness 0.15)
				)
			)
		)
		(property "Dielectric" "X5R"
			(at 0 0 270)
			(unlocked yes)
			(layer "F.Fab")
			(hide yes)
			(effects
				(font
					(size 1 1)
					(thickness 0.15)
				)
			)
		)
		(property "Public" "False"
			(at 0 0 270)
			(unlocked yes)
			(layer "F.Fab")
			(hide yes)
			(effects
				(font
					(size 1 1)
					(thickness 0.15)
				)
			)
		)
		(component_classes
			(class "DCDC_20V")
		)
		(sheetname "/DCDC/")
		(sheetfile "dcdc.kicad_sch")
		(attr smd)
		(fp_line
			(start -0.3 0.7)
			(end 0.3 0.7)
			(stroke
				(width 0.15)
				(type solid)
			)
			(layer "F.SilkS")
		)
		(fp_line
			(start -0.3 -0.7)
			(end 0.3 -0.7)
			(stroke
				(width 0.15)
				(type solid)
			)
			(layer "F.SilkS")
		)
		(fp_rect
			(start 1.95 -0.9)
			(end -1.95 0.9)
			(stroke
				(width 0.05)
				(type default)
			)
			(fill no)
			(layer "F.CrtYd")
		)
		(fp_rect
			(start -0.95 -0.675)
			(end 0.95 0.675)
			(stroke
				(width 0.15)
				(type solid)
			)
			(fill no)
			(layer "F.Fab")
		)
		(fp_text user "Author: Antmicro"
			(at -1.9 5.947 90)
			(layer "F.Fab")
			(effects
				(font
					(size 0.7 0.7)
					(thickness 0.15)
				)
				(justify right top)
			)
		)
		(fp_text user "License: Apache-2.0"
			(at -1.9 4.947 90)
			(layer "F.Fab")
			(effects
				(font
					(size 0.7 0.7)
					(thickness 0.15)
				)
				(justify right top)
			)
		)
		(fp_text user "${REFERENCE}"
			(at -1.9 3.947 90)
			(layer "F.Fab")
			(effects
				(font
					(size 0.7 0.7)
					(thickness 0.15)
				)
				(justify right top)
			)
		)
		(pad "1" smd roundrect
			(at -1.1 0 270)
			(size 1.2 1.3)
			(layers "F.Cu" "F.Mask" "F.Paste")
			(roundrect_rratio 0.25)
			(net 1 "GND")
			(pintype "passive")
		)
		(pad "2" smd roundrect
			(at 1.1 0 270)
			(size 1.2 1.3)
			(layers "F.Cu" "F.Mask" "F.Paste")
			(roundrect_rratio 0.25)
			(net 1105 "/DCDC/20V_OUT")
			(pintype "passive")
		)
	)
	(footprint "antmicro-footprints:TP_SMD_0.75mm"
		(layer "F.Cu")
		(at 164.03 57.14 180)
		(property "Reference" "TP42"
			(at 1.49 0.39 90)
			(layer "F.SilkS")
			(hide yes)
			(effects
				(font
					(size 0.7 0.7)
					(thickness 0.15)
				)
				(justify right top)
			)
		)
		(property "Value" "TP_0.75mm_SMD"
			(at 0 1.2 0)
			(layer "F.Fab")
			(effects
				(font
					(size 0.7 0.7)
					(thickness 0.15)
				)
				(justify right top)
			)
		)
		(property "Description" "SMT test point"
			(at 0 0 0)
			(layer "F.Fab")
			(hide yes)
			(effects
				(font
					(size 1.27 1.27)
					(thickness 0.15)
				)
			)
		)
		(property "MPN" ""
			(at 0 0 180)
			(unlocked yes)
			(layer "F.Fab")
			(hide yes)
			(effects
				(font
					(size 1 1)
					(thickness 0.15)
				)
			)
		)
		(property "Manufacturer" ""
			(at 0 0 180)
			(unlocked yes)
			(layer "F.Fab")
			(hide yes)
			(effects
				(font
					(size 1 1)
					(thickness 0.15)
				)
			)
		)
		(property "Author" "Antmicro"
			(at 0 0 180)
			(unlocked yes)
			(layer "F.Fab")
			(hide yes)
			(effects
				(font
					(size 1 1)
					(thickness 0.15)
				)
			)
		)
		(property "License" "Apache-2.0"
			(at 0 0 180)
			(unlocked yes)
			(layer "F.Fab")
			(hide yes)
			(effects
				(font
					(size 1 1)
					(thickness 0.15)
				)
			)
		)
		(sheetname "/Power/")
		(sheetfile "power.kicad_sch")
		(attr exclude_from_pos_files exclude_from_bom)
		(fp_circle
			(center 0 0)
			(end 0.475 0)
			(stroke
				(width 0.05)
				(type default)
			)
			(fill no)
			(layer "F.CrtYd")
		)
		(fp_text user "Author: Antmicro"
			(at -0.4 3.901 0)
			(layer "F.Fab")
			(effects
				(font
					(size 0.7 0.7)
					(thickness 0.15)
				)
				(justify right top)
			)
		)
		(fp_text user "${REFERENCE}"
			(at -0.4 2.7 0)
			(layer "F.Fab")
			(effects
				(font
					(size 0.7 0.7)
					(thickness 0.15)
				)
				(justify right top)
			)
		)
		(fp_text user "License: Apache-2.0"
			(at -0.4 5.101 0)
			(layer "F.Fab")
			(effects
				(font
					(size 0.7 0.7)
					(thickness 0.15)
				)
				(justify right top)
			)
		)
		(pad "1" smd circle
			(at 0 0 180)
			(size 0.75 0.75)
			(layers "F.Cu" "F.Mask")
			(net 11 "+1V8")
			(pinfunction "1")
			(pintype "passive")
		)
	)
	(footprint "antmicro-footprints:R_0402_1005Metric"
		(layer "F.Cu")
		(at 167.95 144.8 90)
		(descr "Resistor SMD 0402")
		(tags "resistor SMD 0402")
		(property "Reference" "R25"
			(at -1 1.35 90)
			(layer "F.SilkS")
			(effects
				(font
					(size 0.7 0.7)
					(thickness 0.15)
				)
				(justify left bottom)
			)
		)
		(property "Value" "R_0R_0402"
			(at -1.011843 1.772047 90)
			(layer "F.Fab")
			(effects
				(font
					(size 0.7 0.7)
					(thickness 0.15)
				)
				(justify left bottom)
			)
		)
		(property "Datasheet" "https://industrial.panasonic.com/cdbs/www-data/pdf/RDA0000/AOA0000C301.pdf"
			(at 0 0 90)
			(layer "F.Fab")
			(hide yes)
			(effects
				(font
					(size 1.27 1.27)
					(thickness 0.15)
				)
			)
		)
		(property "Description" "SMD Chip Resistor, Jumper, 0 ohm, 100 mW, 0402 [1005 Metric], Thick Film, General Purpose"
			(at 0 0 90)
			(layer "F.Fab")
			(hide yes)
			(effects
				(font
					(size 1.27 1.27)
					(thickness 0.15)
				)
			)
		)
		(property "MPN" "ERJ2GE0R00X"
			(at 0 0 90)
			(unlocked yes)
			(layer "F.Fab")
			(hide yes)
			(effects
				(font
					(size 1 1)
					(thickness 0.15)
				)
			)
		)
		(property "Manufacturer" "Panasonic"
			(at 0 0 90)
			(unlocked yes)
			(layer "F.Fab")
			(hide yes)
			(effects
				(font
					(size 1 1)
					(thickness 0.15)
				)
			)
		)
		(property "License" "Apache-2.0"
			(at 0 0 90)
			(unlocked yes)
			(layer "F.Fab")
			(hide yes)
			(effects
				(font
					(size 1 1)
					(thickness 0.15)
				)
			)
		)
		(property "Author" "Antmicro"
			(at 0 0 90)
			(unlocked yes)
			(layer "F.Fab")
			(hide yes)
			(effects
				(font
					(size 1 1)
					(thickness 0.15)
				)
			)
		)
		(property "Val" "0R"
			(at 0 0 90)
			(unlocked yes)
			(layer "F.Fab")
			(hide yes)
			(effects
				(font
					(size 1 1)
					(thickness 0.15)
				)
			)
		)
		(property "Tolerance" "~"
			(at 0 0 90)
			(unlocked yes)
			(layer "F.Fab")
			(hide yes)
			(effects
				(font
					(size 1 1)
					(thickness 0.15)
				)
			)
		)
		(property "Current" "1A"
			(at 0 0 90)
			(unlocked yes)
			(layer "F.Fab")
			(hide yes)
			(effects
				(font
					(size 1 1)
					(thickness 0.15)
				)
			)
		)
		(sheetname "/Peripherals/")
		(sheetfile "peripherals.kicad_sch")
		(attr smd exclude_from_pos_files exclude_from_bom dnp)
		(fp_rect
			(start -0.925 -0.47)
			(end 0.925 0.47)
			(stroke
				(width 0.05)
				(type default)
			)
			(fill no)
			(layer "F.CrtYd")
		)
		(fp_rect
			(start -0.5 -0.25)
			(end 0.5 0.25)
			(stroke
				(width 0.15)
				(type solid)
			)
			(fill no)
			(layer "F.Fab")
		)
		(fp_text user "${REFERENCE}"
			(at -0.95 3.168 90)
			(layer "F.Fab")
			(effects
				(font
					(size 0.7 0.7)
					(thickness 0.15)
				)
				(justify left bottom)
			)
		)
		(fp_text user "License: Apache-2.0"
			(at -0.95 5.169 90)
			(layer "F.Fab")
			(effects
				(font
					(size 0.7 0.7)
					(thickness 0.15)
				)
				(justify left bottom)
			)
		)
		(fp_text user "Author: Antmicro"
			(at -0.95 4.169 90)
			(layer "F.Fab")
			(effects
				(font
					(size 0.7 0.7)
					(thickness 0.15)
				)
				(justify left bottom)
			)
		)
		(pad "1" smd roundrect
			(at -0.48 0 90)
			(size 0.59 0.64)
			(layers "F.Cu" "F.Mask" "F.Paste")
			(roundrect_rratio 0.25)
			(net 634 "+12V")
			(pintype "passive")
		)
		(pad "2" smd roundrect
			(at 0.48 0 90)
			(size 0.59 0.64)
			(layers "F.Cu" "F.Mask" "F.Paste")
			(roundrect_rratio 0.25)
			(net 1043 "/Peripherals/FAN_VDD")
			(pintype "passive")
		)
	)
	(footprint "antmicro-footprints:C_0603_1608Metric_EIA"
		(layer "F.Cu")
		(at 147.954391 126.46)
		(descr "Capacitor SMD 0603, IPC-7351 Density Level A")
		(tags "Capacitor 0603")
		(property "Reference" "C37"
			(at 1.145609 0.44 0)
			(layer "F.SilkS")
			(effects
				(font
					(size 0.7 0.7)
					(thickness 0.15)
				)
				(justify left bottom)
			)
		)
		(property "Value" "C_22u_16V_0603"
			(at -1.42757 1.770288 0)
			(layer "F.Fab")
			(effects
				(font
					(size 0.7 0.7)
					(thickness 0.15)
				)
				(justify left bottom)
			)
		)
		(property "Datasheet" "https://product.samsungsem.com/mlcc/CL10A226MO7JZN.do"
			(at 0 0 0)
			(layer "F.Fab")
			(hide yes)
			(effects
				(font
					(size 1.27 1.27)
					(thickness 0.15)
				)
			)
		)
		(property "Description" "SMD Multilayer Ceramic Capacitor"
			(at 0 0 0)
			(layer "F.Fab")
			(hide yes)
			(effects
				(font
					(size 1.27 1.27)
					(thickness 0.15)
				)
			)
		)
		(property "MPN" "CL10A226MO7JZNC"
			(at 0 0 0)
			(unlocked yes)
			(layer "F.Fab")
			(hide yes)
			(effects
				(font
					(size 1 1)
					(thickness 0.15)
				)
			)
		)
		(property "Manufacturer" "Samsung Electro-Mechanics"
			(at 0 0 0)
			(unlocked yes)
			(layer "F.Fab")
			(hide yes)
			(effects
				(font
					(size 1 1)
					(thickness 0.15)
				)
			)
		)
		(property "License" "Apache-2.0"
			(at 0 0 0)
			(unlocked yes)
			(layer "F.Fab")
			(hide yes)
			(effects
				(font
					(size 1 1)
					(thickness 0.15)
				)
			)
		)
		(property "Author" "Antmicro"
			(at 0 0 0)
			(unlocked yes)
			(layer "F.Fab")
			(hide yes)
			(effects
				(font
					(size 1 1)
					(thickness 0.15)
				)
			)
		)
		(property "Val" "22u"
			(at 0 0 0)
			(unlocked yes)
			(layer "F.Fab")
			(hide yes)
			(effects
				(font
					(size 1 1)
					(thickness 0.15)
				)
			)
		)
		(property "Voltage" "16V"
			(at 0 0 0)
			(unlocked yes)
			(layer "F.Fab")
			(hide yes)
			(effects
				(font
					(size 1 1)
					(thickness 0.15)
				)
			)
		)
		(property "Dielectric" ""
			(at 0 0 0)
			(unlocked yes)
			(layer "F.Fab")
			(hide yes)
			(effects
				(font
					(size 1 1)
					(thickness 0.15)
				)
			)
		)
		(component_classes
			(class "DCDC_1V8")
		)
		(sheetname "/DCDC/")
		(sheetfile "dcdc.kicad_sch")
		(attr smd)
		(fp_line
			(start -0.15 -0.55)
			(end 0.15 -0.55)
			(stroke
				(width 0.15)
				(type solid)
			)
			(layer "F.SilkS")
		)
		(fp_line
			(start -0.15 0.55)
			(end 0.15 0.55)
			(stroke
				(width 0.15)
				(type solid)
			)
			(layer "F.SilkS")
		)
		(fp_rect
			(start -1.25 -0.65)
			(end 1.25 0.65)
			(stroke
				(width 0.05)
				(type solid)
			)
			(fill no)
			(layer "F.CrtYd")
		)
		(fp_rect
			(start -0.8 -0.45)
			(end 0.8 0.45)
			(stroke
				(width 0.15)
				(type solid)
			)
			(fill no)
			(layer "F.Fab")
		)
		(fp_text user "License: Apache-2.0"
			(at -1.682 5.895 0)
			(layer "F.Fab")
			(effects
				(font
					(size 0.7 0.7)
					(thickness 0.15)
				)
				(justify left bottom)
			)
		)
		(fp_text user "Author: Antmicro"
			(at -1.682 4.894 0)
			(layer "F.Fab")
			(effects
				(font
					(size 0.7 0.7)
					(thickness 0.15)
				)
				(justify left bottom)
			)
		)
		(fp_text user "${REFERENCE}"
			(at -1.682 3.895 0)
			(layer "F.Fab")
			(effects
				(font
					(size 0.7 0.7)
					(thickness 0.15)
				)
				(justify left bottom)
			)
		)
		(pad "1" smd roundrect
			(at -0.7 0)
			(size 0.8 1.1)
			(layers "F.Cu" "F.Mask" "F.Paste")
			(roundrect_rratio 0.2)
			(net 1 "GND")
			(pintype "passive")
		)
		(pad "2" smd roundrect
			(at 0.7 0)
			(size 0.8 1.1)
			(layers "F.Cu" "F.Mask" "F.Paste")
			(roundrect_rratio 0.2)
			(net 17 "/DCDC/1V8_OUT")
			(pintype "passive")
		)
	)
	(footprint "antmicro-footprints:C_0402_1005Metric"
		(layer "F.Cu")
		(at 197.2 127.3)
		(descr "Capacitor SMD 0402")
		(tags "capacitor SMD 0402")
		(property "Reference" "C89"
			(at -1 1.4 0)
			(layer "F.SilkS")
			(effects
				(font
					(size 0.7 0.7)
					(thickness 0.15)
				)
				(justify left bottom)
			)
		)
		(property "Value" "C_100n_0402"
			(at -1.022927 2.155213 0)
			(layer "F.Fab")
			(effects
				(font
					(size 0.7 0.7)
					(thickness 0.15)
				)
				(justify left bottom)
			)
		)
		(property "Datasheet" "https://www.murata.com/products/productdetail?partno=GRM155R61H104KE14%23"
			(at 0 0 0)
			(layer "F.Fab")
			(hide yes)
			(effects
				(font
					(size 1.27 1.27)
					(thickness 0.15)
				)
			)
		)
		(property "Description" "SMD Multilayer Ceramic Capacitor, 0.1 µF, 50 V, 0402 [1005 Metric], ± 10%, X5R, GRM Series"
			(at 0 0 0)
			(layer "F.Fab")
			(hide yes)
			(effects
				(font
					(size 1.27 1.27)
					(thickness 0.15)
				)
			)
		)
		(property "MPN" "GRM155R61H104KE14D"
			(at 0 0 0)
			(unlocked yes)
			(layer "F.Fab")
			(hide yes)
			(effects
				(font
					(size 1 1)
					(thickness 0.15)
				)
			)
		)
		(property "Val" "100n"
			(at 0 0 0)
			(unlocked yes)
			(layer "F.Fab")
			(hide yes)
			(effects
				(font
					(size 1 1)
					(thickness 0.15)
				)
			)
		)
		(property "Voltage" "50V"
			(at 0 0 0)
			(unlocked yes)
			(layer "F.Fab")
			(hide yes)
			(effects
				(font
					(size 1 1)
					(thickness 0.15)
				)
			)
		)
		(property "Dielectric" "X5R"
			(at 0 0 0)
			(unlocked yes)
			(layer "F.Fab")
			(hide yes)
			(effects
				(font
					(size 1 1)
					(thickness 0.15)
				)
			)
		)
		(property "Manufacturer" "Murata"
			(at 0 0 0)
			(unlocked yes)
			(layer "F.Fab")
			(hide yes)
			(effects
				(font
					(size 1 1)
					(thickness 0.15)
				)
			)
		)
		(property "License" "Apache-2.0"
			(at 0 0 0)
			(unlocked yes)
			(layer "F.Fab")
			(hide yes)
			(effects
				(font
					(size 1 1)
					(thickness 0.15)
				)
			)
		)
		(property "Author" "Antmicro"
			(at 0 0 0)
			(unlocked yes)
			(layer "F.Fab")
			(hide yes)
			(effects
				(font
					(size 1 1)
					(thickness 0.15)
				)
			)
		)
		(sheetname "/USB Hub/")
		(sheetfile "usb_hub.kicad_sch")
		(attr smd)
		(fp_rect
			(start -0.925 -0.47)
			(end 0.925 0.47)
			(stroke
				(width 0.05)
				(type default)
			)
			(fill no)
			(layer "F.CrtYd")
		)
		(fp_line
			(start -0.494 -0.25)
			(end 0.504 -0.25)
			(stroke
				(width 0.15)
				(type solid)
			)
			(layer "F.Fab")
		)
		(fp_line
			(start -0.494 0.248)
			(end -0.494 -0.25)
			(stroke
				(width 0.15)
				(type solid)
			)
			(layer "F.Fab")
		)
		(fp_line
			(start 0.504 -0.25)
			(end 0.504 0.248)
			(stroke
				(width 0.15)
				(type solid)
			)
			(layer "F.Fab")
		)
		(fp_line
			(start 0.504 0.248)
			(end -0.494 0.248)
			(stroke
				(width 0.15)
				(type solid)
			)
			(layer "F.Fab")
		)
		(fp_text user "Author: Antmicro"
			(at -0.939 3.399 0)
			(layer "F.Fab")
			(effects
				(font
					(size 0.7 0.7)
					(thickness 0.15)
				)
				(justify left bottom)
			)
		)
		(fp_text user "${REFERENCE}"
			(at -0.939 4.599 0)
			(layer "F.Fab")
			(effects
				(font
					(size 0.7 0.7)
					(thickness 0.15)
				)
				(justify left bottom)
			)
		)
		(fp_text user "License: Apache-2.0"
			(at -0.939 5.799 0)
			(layer "F.Fab")
			(effects
				(font
					(size 0.7 0.7)
					(thickness 0.15)
				)
				(justify left bottom)
			)
		)
		(pad "1" smd roundrect
			(at -0.48 0)
			(size 0.59 0.64)
			(layers "F.Cu" "F.Mask" "F.Paste")
			(roundrect_rratio 0.25)
			(net 1 "GND")
			(pintype "passive")
		)
		(pad "2" smd roundrect
			(at 0.48 0)
			(size 0.59 0.64)
			(layers "F.Cu" "F.Mask" "F.Paste")
			(roundrect_rratio 0.25)
			(net 2 "+3V3")
			(pintype "passive")
		)
	)
)
